# S9S_MB_2U (Grand Teton) — schematic netlist excerpt (pin names and nets, part order shuffled) for the footprints in the layout excerpt that follows; sources: Cadence DE-HDL packaged netlist, KiCad conversion of 03242023_DA0F0TMBIJ0_F0T_Motherboard_J_brd_V01_OCP.brd

PC374  Q_CAP  3300PF 50V 10% X7R  pkg 0402  page 297 : A = SW_P12V_PVCCINFAON_CPU1_FLT ; B = GND
PR435  Q_RES  10K 1% EMPTY  pkg 0402LF  page 274 : A = PVCCINFAON_CPU0_ATSEN ; B = GND

(kicad_pcb
	(version 20260206)
	(generator "pcbnew")
	(generator_version "10.0")
	(general
		(thickness 1.6)
		(legacy_teardrops no)
	)
	(paper "A4")
	(title_block
		(title "03242023_DA0F0TMBIJ0_F0T_Motherboard_J_brd_V01_OCP.brd")
		(comment 1 "Grand Teton / footprints 1402-1403 of 6105")
	)
	(layers
		(0 "F.Cu" signal "TOP")
		(4 "In1.Cu" signal "GND")
		(6 "In2.Cu" signal "IN1")
		(8 "In3.Cu" signal "GND1")
		(10 "In4.Cu" signal "IN2")
		(12 "In5.Cu" signal "GND2")
		(14 "In6.Cu" signal "IN3")
		(16 "In7.Cu" signal "GND3")
		(18 "In8.Cu" signal "VCC")
		(20 "In9.Cu" signal "VCC1")
		(22 "In10.Cu" signal "GND4")
		(24 "In11.Cu" signal "IN4")
		(26 "In12.Cu" signal "GND5")
		(28 "In13.Cu" signal "IN5")
		(30 "In14.Cu" signal "GND6")
		(32 "In15.Cu" signal "IN6")
		(34 "In16.Cu" signal "GND7")
		(2 "B.Cu" signal "BOTTOM")
		(9 "F.Adhes" user "F.Adhesive")
		(11 "B.Adhes" user "B.Adhesive")
		(13 "F.Paste" user "Package Geometry/Pastemask Top")
		(15 "B.Paste" user "Package Geometry/Pastemask Bottom")
		(5 "F.SilkS" user "Ref Des/Silkscreen Top")
		(7 "B.SilkS" user "Ref Des/Silkscreen Bottom")
		(1 "F.Mask" user "Board Geometry/Soldermask Top")
		(3 "B.Mask" user "Board Geometry/Soldermask Bottom")
		(17 "Dwgs.User" user "User.Drawings")
		(19 "Cmts.User" user "User.Comments")
		(21 "Eco1.User" user "User.Eco1")
		(23 "Eco2.User" user "User.Eco2")
		(25 "Edge.Cuts" user "Board Geometry/Outline")
		(27 "Margin" user)
		(31 "F.CrtYd" user "Package Geometry/Place Bound Top")
		(29 "B.CrtYd" user "Package Geometry/Place Bound Bottom")
		(35 "F.Fab" user "Ref Des/Assembly Top")
		(33 "B.Fab" user "Ref Des/Assembly Bottom")
	)
	(footprint ""
		(layer "F.Cu")
		(at 49.139094 -169.708322 90)
		(property "Reference" "PC374"
			(at 0 0 90)
			(layer "F.SilkS")
			(hide yes)
			(effects
				(font
					(size 1.27 1.27)
				)
			)
		)
		(property "Value" ""
			(at 0 0 90)
			(layer "F.Fab")
			(effects
				(font
					(size 1.27 1.27)
				)
			)
		)
		(duplicate_pad_numbers_are_jumpers no)
		(fp_line
			(start 0.7874 -0.4064)
			(end 0.7874 0.4064)
			(stroke
				(width 0.1524)
				(type default)
			)
			(layer "F.SilkS")
		)
		(fp_line
			(start -0.7874 -0.4064)
			(end 0.7874 -0.4064)
			(stroke
				(width 0.1524)
				(type default)
			)
			(layer "F.SilkS")
		)
		(fp_line
			(start 0.7874 0.4064)
			(end -0.7874 0.4064)
			(stroke
				(width 0.1524)
				(type default)
			)
			(layer "F.SilkS")
		)
		(fp_line
			(start -0.7874 0.4064)
			(end -0.7874 -0.4064)
			(stroke
				(width 0.1524)
				(type default)
			)
			(layer "F.SilkS")
		)
		(fp_line
			(start -0.12065 -0.305054)
			(end -0.12065 -0.2794)
			(stroke
				(width 0.1)
				(type default)
			)
			(layer "F.Fab")
		)
		(fp_line
			(start -0.67945 -0.305054)
			(end -0.12065 -0.305054)
			(stroke
				(width 0.1)
				(type default)
			)
			(layer "F.Fab")
		)
		(fp_line
			(start 0.67945 -0.3048)
			(end 0.67945 0.3048)
			(stroke
				(width 0.1)
				(type default)
			)
			(layer "F.Fab")
		)
		(fp_line
			(start 0.12065 -0.3048)
			(end 0.67945 -0.3048)
			(stroke
				(width 0.1)
				(type default)
			)
			(layer "F.Fab")
		)
		(fp_line
			(start 0.12065 -0.2794)
			(end 0.12065 -0.3048)
			(stroke
				(width 0.1)
				(type default)
			)
			(layer "F.Fab")
		)
		(fp_line
			(start -0.12065 -0.2794)
			(end 0.12065 -0.2794)
			(stroke
				(width 0.1)
				(type default)
			)
			(layer "F.Fab")
		)
		(fp_line
			(start 0.120396 0.2794)
			(end -0.12065 0.2794)
			(stroke
				(width 0.1)
				(type default)
			)
			(layer "F.Fab")
		)
		(fp_line
			(start -0.12065 0.2794)
			(end -0.12065 0.3048)
			(stroke
				(width 0.1)
				(type default)
			)
			(layer "F.Fab")
		)
		(fp_line
			(start 0.67945 0.3048)
			(end 0.120396 0.3048)
			(stroke
				(width 0.1)
				(type default)
			)
			(layer "F.Fab")
		)
		(fp_line
			(start 0.120396 0.3048)
			(end 0.120396 0.2794)
			(stroke
				(width 0.1)
				(type default)
			)
			(layer "F.Fab")
		)
		(fp_line
			(start -0.12065 0.3048)
			(end -0.67945 0.3048)
			(stroke
				(width 0.1)
				(type default)
			)
			(layer "F.Fab")
		)
		(fp_line
			(start -0.67945 0.3048)
			(end -0.67945 -0.305054)
			(stroke
				(width 0.1)
				(type default)
			)
			(layer "F.Fab")
		)
		(pad "1" smd circle
			(at -0.40005 0 90)
			(size 0 0)
			(layers "F.Cu" "F.Mask" "F.Paste")
			(net "SW_P12V_PVCCINFAON_CPU1_FLT")
		)
		(pad "2" smd circle
			(at 0.40005 0 90)
			(size 0 0)
			(layers "F.Cu" "F.Mask" "F.Paste")
			(net "GND")
		)
	)
	(footprint ""
		(layer "F.Cu")
		(at 418.919914 -139.88669 90)
		(property "Reference" "PR435"
			(at 0 0 90)
			(layer "F.SilkS")
			(hide yes)
			(effects
				(font
					(size 1.27 1.27)
				)
			)
		)
		(property "Value" ""
			(at 0 0 90)
			(layer "F.Fab")
			(effects
				(font
					(size 1.27 1.27)
				)
			)
		)
		(duplicate_pad_numbers_are_jumpers no)
		(fp_line
			(start 0.7874 -0.4064)
			(end 0.7874 0.4064)
			(stroke
				(width 0.1524)
				(type default)
			)
			(layer "F.SilkS")
		)
		(fp_line
			(start -0.7874 -0.4064)
			(end 0.7874 -0.4064)
			(stroke
				(width 0.1524)
				(type default)
			)
			(layer "F.SilkS")
		)
		(fp_line
			(start 0.7874 0.4064)
			(end -0.7874 0.4064)
			(stroke
				(width 0.1524)
				(type default)
			)
			(layer "F.SilkS")
		)
		(fp_line
			(start -0.7874 0.4064)
			(end -0.7874 -0.4064)
			(stroke
				(width 0.1524)
				(type default)
			)
			(layer "F.SilkS")
		)
		(fp_line
			(start -0.12065 -0.305054)
			(end -0.12065 -0.2794)
			(stroke
				(width 0.1)
				(type default)
			)
			(layer "F.Fab")
		)
		(fp_line
			(start -0.67945 -0.305054)
			(end -0.12065 -0.305054)
			(stroke
				(width 0.1)
				(type default)
			)
			(layer "F.Fab")
		)
		(fp_line
			(start 0.67945 -0.3048)
			(end 0.67945 0.3048)
			(stroke
				(width 0.1)
				(type default)
			)
			(layer "F.Fab")
		)
		(fp_line
			(start 0.12065 -0.3048)
			(end 0.67945 -0.3048)
			(stroke
				(width 0.1)
				(type default)
			)
			(layer "F.Fab")
		)
		(fp_line
			(start 0.12065 -0.2794)
			(end 0.12065 -0.3048)
			(stroke
				(width 0.1)
				(type default)
			)
			(layer "F.Fab")
		)
		(fp_line
			(start -0.12065 -0.2794)
			(end 0.12065 -0.2794)
			(stroke
				(width 0.1)
				(type default)
			)
			(layer "F.Fab")
		)
		(fp_line
			(start 0.120396 0.2794)
			(end -0.12065 0.2794)
			(stroke
				(width 0.1)
				(type default)
			)
			(layer "F.Fab")
		)
		(fp_line
			(start -0.12065 0.2794)
			(end -0.12065 0.3048)
			(stroke
				(width 0.1)
				(type default)
			)
			(layer "F.Fab")
		)
		(fp_line
			(start 0.67945 0.3048)
			(end 0.120396 0.3048)
			(stroke
				(width 0.1)
				(type default)
			)
			(layer "F.Fab")
		)
		(fp_line
			(start 0.120396 0.3048)
			(end 0.120396 0.2794)
			(stroke
				(width 0.1)
				(type default)
			)
			(layer "F.Fab")
		)
		(fp_line
			(start -0.12065 0.3048)
			(end -0.67945 0.3048)
			(stroke
				(width 0.1)
				(type default)
			)
			(layer "F.Fab")
		)
		(fp_line
			(start -0.67945 0.3048)
			(end -0.67945 -0.305054)
			(stroke
				(width 0.1)
				(type default)
			)
			(layer "F.Fab")
		)
		(pad "1" smd circle
			(at -0.40005 0 90)
			(size 0 0)
			(layers "F.Cu" "F.Mask" "F.Paste")
			(net "PVCCINFAON_CPU0_ATSEN")
		)
		(pad "2" smd circle
			(at 0.40005 0 90)
			(size 0 0)
			(layers "F.Cu" "F.Mask" "F.Paste")
			(net "GND")
		)
	)
)
